(kicad_pcb
	(version 20260206)
	(generator "pcbnew")
	(generator_version "10.0")
	(general
		(thickness 1.6)
		(legacy_teardrops no)
	)
	(paper "A4")
	(title_block
		(title "01162023_DA0F0TEBIF0_F0T_Expander_BD_F_brd_V02_OCP.brd")
		(comment 1 "Grand Teton / footprints 5319-5325 of 9728")
	)
	(layers
		(0 "F.Cu" signal "TOP")
		(4 "In1.Cu" signal "GND")
		(6 "In2.Cu" signal "VCC")
		(8 "In3.Cu" signal "VCC1")
		(10 "In4.Cu" signal "GND1")
		(12 "In5.Cu" signal "IN1")
		(14 "In6.Cu" signal "GND2")
		(16 "In7.Cu" signal "IN2")
		(18 "In8.Cu" signal "GND3")
		(20 "In9.Cu" signal "IN3")
		(22 "In10.Cu" signal "GND4")
		(24 "In11.Cu" signal "IN4")
		(26 "In12.Cu" signal "GND5")
		(28 "In13.Cu" signal "IN5")
		(30 "In14.Cu" signal "GND6")
		(32 "In15.Cu" signal "IN6")
		(34 "In16.Cu" signal "GND7")
		(2 "B.Cu" signal "BOTTOM")
		(9 "F.Adhes" user "F.Adhesive")
		(11 "B.Adhes" user "B.Adhesive")
		(13 "F.Paste" user "Package Geometry/Pastemask Top")
		(15 "B.Paste" user "Package Geometry/Pastemask Bottom")
		(5 "F.SilkS" user "Ref Des/Silkscreen Top")
		(7 "B.SilkS" user "Ref Des/Silkscreen Bottom")
		(1 "F.Mask" user "Board Geometry/Soldermask Top")
		(3 "B.Mask" user "Board Geometry/Soldermask Bottom")
		(17 "Dwgs.User" user "User.Drawings")
		(19 "Cmts.User" user "User.Comments")
		(21 "Eco1.User" user "User.Eco1")
		(23 "Eco2.User" user "User.Eco2")
		(25 "Edge.Cuts" user "Board Geometry/Outline")
		(27 "Margin" user)
		(31 "F.CrtYd" user "Package Geometry/Place Bound Top")
		(29 "B.CrtYd" user "Package Geometry/Place Bound Bottom")
		(35 "F.Fab" user "Ref Des/Assembly Top")
		(33 "B.Fab" user "Ref Des/Assembly Bottom")
	)
	(footprint ""
		(layer "F.Cu")
		(at 253.99746 -195.573396 90)
		(property "Reference" "R5644"
			(at 0 0 90)
			(layer "F.SilkS")
			(hide yes)
			(effects
				(font
					(size 1.27 1.27)
				)
			)
		)
		(property "Value" ""
			(at 0 0 90)
			(layer "F.Fab")
			(effects
				(font
					(size 1.27 1.27)
				)
			)
		)
		(duplicate_pad_numbers_are_jumpers no)
		(fp_line
			(start 0.7874 -0.4064)
			(end 0.7874 0.4064)
			(stroke
				(width 0.1524)
				(type default)
			)
			(layer "F.SilkS")
		)
		(fp_line
			(start -0.7874 -0.4064)
			(end 0.7874 -0.4064)
			(stroke
				(width 0.1524)
				(type default)
			)
			(layer "F.SilkS")
		)
		(fp_line
			(start 0.7874 0.4064)
			(end -0.7874 0.4064)
			(stroke
				(width 0.1524)
				(type default)
			)
			(layer "F.SilkS")
		)
		(fp_line
			(start -0.7874 0.4064)
			(end -0.7874 -0.4064)
			(stroke
				(width 0.1524)
				(type default)
			)
			(layer "F.SilkS")
		)
		(fp_line
			(start -0.12065 -0.305054)
			(end -0.12065 -0.2794)
			(stroke
				(width 0.1)
				(type default)
			)
			(layer "F.Fab")
		)
		(fp_line
			(start -0.67945 -0.305054)
			(end -0.12065 -0.305054)
			(stroke
				(width 0.1)
				(type default)
			)
			(layer "F.Fab")
		)
		(fp_line
			(start 0.67945 -0.3048)
			(end 0.67945 0.3048)
			(stroke
				(width 0.1)
				(type default)
			)
			(layer "F.Fab")
		)
		(fp_line
			(start 0.12065 -0.3048)
			(end 0.67945 -0.3048)
			(stroke
				(width 0.1)
				(type default)
			)
			(layer "F.Fab")
		)
		(fp_line
			(start 0.12065 -0.2794)
			(end 0.12065 -0.3048)
			(stroke
				(width 0.1)
				(type default)
			)
			(layer "F.Fab")
		)
		(fp_line
			(start -0.12065 -0.2794)
			(end 0.12065 -0.2794)
			(stroke
				(width 0.1)
				(type default)
			)
			(layer "F.Fab")
		)
		(fp_line
			(start 0.120396 0.2794)
			(end -0.12065 0.2794)
			(stroke
				(width 0.1)
				(type default)
			)
			(layer "F.Fab")
		)
		(fp_line
			(start -0.12065 0.2794)
			(end -0.12065 0.3048)
			(stroke
				(width 0.1)
				(type default)
			)
			(layer "F.Fab")
		)
		(fp_line
			(start 0.67945 0.3048)
			(end 0.120396 0.3048)
			(stroke
				(width 0.1)
				(type default)
			)
			(layer "F.Fab")
		)
		(fp_line
			(start 0.120396 0.3048)
			(end 0.120396 0.2794)
			(stroke
				(width 0.1)
				(type default)
			)
			(layer "F.Fab")
		)
		(fp_line
			(start -0.12065 0.3048)
			(end -0.67945 0.3048)
			(stroke
				(width 0.1)
				(type default)
			)
			(layer "F.Fab")
		)
		(fp_line
			(start -0.67945 0.3048)
			(end -0.67945 -0.305054)
			(stroke
				(width 0.1)
				(type default)
			)
			(layer "F.Fab")
		)
		(pad "1" smd circle
			(at -0.40005 0 90)
			(size 0 0)
			(layers "F.Cu" "F.Mask" "F.Paste")
			(net "JTAG_BIC_TMS_R")
		)
		(pad "2" smd circle
			(at 0.40005 0 90)
			(size 0 0)
			(layers "F.Cu" "F.Mask" "F.Paste")
			(net "JTAG_BIC_TMS_R1")
		)
	)
	(footprint ""
		(layer "F.Cu")
		(at 409.793948 -165.670484 -90)
		(property "Reference" "R2469"
			(at 0 0 270)
			(layer "F.SilkS")
			(hide yes)
			(effects
				(font
					(size 1.27 1.27)
				)
			)
		)
		(property "Value" ""
			(at 0 0 270)
			(layer "F.Fab")
			(effects
				(font
					(size 1.27 1.27)
				)
			)
		)
		(duplicate_pad_numbers_are_jumpers no)
		(fp_line
			(start -0.7874 0.4064)
			(end -0.7874 -0.4064)
			(stroke
				(width 0.1524)
				(type default)
			)
			(layer "F.SilkS")
		)
		(fp_line
			(start 0.7874 0.4064)
			(end -0.7874 0.4064)
			(stroke
				(width 0.1524)
				(type default)
			)
			(layer "F.SilkS")
		)
		(fp_line
			(start -0.7874 -0.4064)
			(end 0.7874 -0.4064)
			(stroke
				(width 0.1524)
				(type default)
			)
			(layer "F.SilkS")
		)
		(fp_line
			(start 0.7874 -0.4064)
			(end 0.7874 0.4064)
			(stroke
				(width 0.1524)
				(type default)
			)
			(layer "F.SilkS")
		)
		(fp_line
			(start -0.67945 0.3048)
			(end -0.67945 -0.305054)
			(stroke
				(width 0.1)
				(type default)
			)
			(layer "F.Fab")
		)
		(fp_line
			(start -0.12065 0.3048)
			(end -0.67945 0.3048)
			(stroke
				(width 0.1)
				(type default)
			)
			(layer "F.Fab")
		)
		(fp_line
			(start 0.120396 0.3048)
			(end 0.120396 0.2794)
			(stroke
				(width 0.1)
				(type default)
			)
			(layer "F.Fab")
		)
		(fp_line
			(start 0.67945 0.3048)
			(end 0.120396 0.3048)
			(stroke
				(width 0.1)
				(type default)
			)
			(layer "F.Fab")
		)
		(fp_line
			(start -0.12065 0.2794)
			(end -0.12065 0.3048)
			(stroke
				(width 0.1)
				(type default)
			)
			(layer "F.Fab")
		)
		(fp_line
			(start 0.120396 0.2794)
			(end -0.12065 0.2794)
			(stroke
				(width 0.1)
				(type default)
			)
			(layer "F.Fab")
		)
		(fp_line
			(start -0.12065 -0.2794)
			(end 0.12065 -0.2794)
			(stroke
				(width 0.1)
				(type default)
			)
			(layer "F.Fab")
		)
		(fp_line
			(start 0.12065 -0.2794)
			(end 0.12065 -0.3048)
			(stroke
				(width 0.1)
				(type default)
			)
			(layer "F.Fab")
		)
		(fp_line
			(start 0.12065 -0.3048)
			(end 0.67945 -0.3048)
			(stroke
				(width 0.1)
				(type default)
			)
			(layer "F.Fab")
		)
		(fp_line
			(start 0.67945 -0.3048)
			(end 0.67945 0.3048)
			(stroke
				(width 0.1)
				(type default)
			)
			(layer "F.Fab")
		)
		(fp_line
			(start -0.67945 -0.305054)
			(end -0.12065 -0.305054)
			(stroke
				(width 0.1)
				(type default)
			)
			(layer "F.Fab")
		)
		(fp_line
			(start -0.12065 -0.305054)
			(end -0.12065 -0.2794)
			(stroke
				(width 0.1)
				(type default)
			)
			(layer "F.Fab")
		)
		(pad "1" smd circle
			(at -0.40005 0 270)
			(size 0 0)
			(layers "F.Cu" "F.Mask" "F.Paste")
			(net "P3V3_NIC6")
		)
		(pad "2" smd circle
			(at 0.40005 0 270)
			(size 0 0)
			(layers "F.Cu" "F.Mask" "F.Paste")
			(net "NIC6_PWRBRK_N")
		)
	)
	(footprint ""
		(layer "F.Cu")
		(at 80.875124 -63.086234)
		(property "Reference" "R5853"
			(at 0 0 0)
			(layer "F.SilkS")
			(hide yes)
			(effects
				(font
					(size 1.27 1.27)
				)
			)
		)
		(property "Value" ""
			(at 0 0 0)
			(layer "F.Fab")
			(effects
				(font
					(size 1.27 1.27)
				)
			)
		)
		(duplicate_pad_numbers_are_jumpers no)
		(fp_line
			(start -0.7874 -0.4064)
			(end 0.7874 -0.4064)
			(stroke
				(width 0.1524)
				(type default)
			)
			(layer "F.SilkS")
		)
		(fp_line
			(start -0.7874 0.4064)
			(end -0.7874 -0.4064)
			(stroke
				(width 0.1524)
				(type default)
			)
			(layer "F.SilkS")
		)
		(fp_line
			(start 0.7874 -0.4064)
			(end 0.7874 0.4064)
			(stroke
				(width 0.1524)
				(type default)
			)
			(layer "F.SilkS")
		)
		(fp_line
			(start 0.7874 0.4064)
			(end -0.7874 0.4064)
			(stroke
				(width 0.1524)
				(type default)
			)
			(layer "F.SilkS")
		)
		(fp_line
			(start -0.67945 -0.305054)
			(end -0.12065 -0.305054)
			(stroke
				(width 0.1)
				(type default)
			)
			(layer "F.Fab")
		)
		(fp_line
			(start -0.67945 0.3048)
			(end -0.67945 -0.305054)
			(stroke
				(width 0.1)
				(type default)
			)
			(layer "F.Fab")
		)
		(fp_line
			(start -0.12065 -0.305054)
			(end -0.12065 -0.2794)
			(stroke
				(width 0.1)
				(type default)
			)
			(layer "F.Fab")
		)
		(fp_line
			(start -0.12065 -0.2794)
			(end 0.12065 -0.2794)
			(stroke
				(width 0.1)
				(type default)
			)
			(layer "F.Fab")
		)
		(fp_line
			(start -0.12065 0.2794)
			(end -0.12065 0.3048)
			(stroke
				(width 0.1)
				(type default)
			)
			(layer "F.Fab")
		)
		(fp_line
			(start -0.12065 0.3048)
			(end -0.67945 0.3048)
			(stroke
				(width 0.1)
				(type default)
			)
			(layer "F.Fab")
		)
		(fp_line
			(start 0.120396 0.2794)
			(end -0.12065 0.2794)
			(stroke
				(width 0.1)
				(type default)
			)
			(layer "F.Fab")
		)
		(fp_line
			(start 0.120396 0.3048)
			(end 0.120396 0.2794)
			(stroke
				(width 0.1)
				(type default)
			)
			(layer "F.Fab")
		)
		(fp_line
			(start 0.12065 -0.3048)
			(end 0.67945 -0.3048)
			(stroke
				(width 0.1)
				(type default)
			)
			(layer "F.Fab")
		)
		(fp_line
			(start 0.12065 -0.2794)
			(end 0.12065 -0.3048)
			(stroke
				(width 0.1)
				(type default)
			)
			(layer "F.Fab")
		)
		(fp_line
			(start 0.67945 -0.3048)
			(end 0.67945 0.3048)
			(stroke
				(width 0.1)
				(type default)
			)
			(layer "F.Fab")
		)
		(fp_line
			(start 0.67945 0.3048)
			(end 0.120396 0.3048)
			(stroke
				(width 0.1)
				(type default)
			)
			(layer "F.Fab")
		)
		(pad "1" smd circle
			(at -0.40005 0)
			(size 0 0)
			(layers "F.Cu" "F.Mask" "F.Paste")
			(net "P12V_SSD3_R")
		)
		(pad "2" smd circle
			(at 0.40005 0)
			(size 0 0)
			(layers "F.Cu" "F.Mask" "F.Paste")
			(net "P12V_SSD3_PG_G1")
		)
	)
	(footprint ""
		(layer "F.Cu")
		(at 121.002044 -32.849312 90)
		(property "Reference" "R5670"
			(at 0 0 90)
			(layer "F.SilkS")
			(hide yes)
			(effects
				(font
					(size 1.27 1.27)
				)
			)
		)
		(property "Value" ""
			(at 0 0 90)
			(layer "F.Fab")
			(effects
				(font
					(size 1.27 1.27)
				)
			)
		)
		(duplicate_pad_numbers_are_jumpers no)
		(fp_line
			(start 0.7874 -0.4064)
			(end 0.7874 0.4064)
			(stroke
				(width 0.1524)
				(type default)
			)
			(layer "F.SilkS")
		)
		(fp_line
			(start -0.7874 -0.4064)
			(end 0.7874 -0.4064)
			(stroke
				(width 0.1524)
				(type default)
			)
			(layer "F.SilkS")
		)
		(fp_line
			(start 0.7874 0.4064)
			(end -0.7874 0.4064)
			(stroke
				(width 0.1524)
				(type default)
			)
			(layer "F.SilkS")
		)
		(fp_line
			(start -0.7874 0.4064)
			(end -0.7874 -0.4064)
			(stroke
				(width 0.1524)
				(type default)
			)
			(layer "F.SilkS")
		)
		(fp_line
			(start -0.12065 -0.305054)
			(end -0.12065 -0.2794)
			(stroke
				(width 0.1)
				(type default)
			)
			(layer "F.Fab")
		)
		(fp_line
			(start -0.67945 -0.305054)
			(end -0.12065 -0.305054)
			(stroke
				(width 0.1)
				(type default)
			)
			(layer "F.Fab")
		)
		(fp_line
			(start 0.67945 -0.3048)
			(end 0.67945 0.3048)
			(stroke
				(width 0.1)
				(type default)
			)
			(layer "F.Fab")
		)
		(fp_line
			(start 0.12065 -0.3048)
			(end 0.67945 -0.3048)
			(stroke
				(width 0.1)
				(type default)
			)
			(layer "F.Fab")
		)
		(fp_line
			(start 0.12065 -0.2794)
			(end 0.12065 -0.3048)
			(stroke
				(width 0.1)
				(type default)
			)
			(layer "F.Fab")
		)
		(fp_line
			(start -0.12065 -0.2794)
			(end 0.12065 -0.2794)
			(stroke
				(width 0.1)
				(type default)
			)
			(layer "F.Fab")
		)
		(fp_line
			(start 0.120396 0.2794)
			(end -0.12065 0.2794)
			(stroke
				(width 0.1)
				(type default)
			)
			(layer "F.Fab")
		)
		(fp_line
			(start -0.12065 0.2794)
			(end -0.12065 0.3048)
			(stroke
				(width 0.1)
				(type default)
			)
			(layer "F.Fab")
		)
		(fp_line
			(start 0.67945 0.3048)
			(end 0.120396 0.3048)
			(stroke
				(width 0.1)
				(type default)
			)
			(layer "F.Fab")
		)
		(fp_line
			(start 0.120396 0.3048)
			(end 0.120396 0.2794)
			(stroke
				(width 0.1)
				(type default)
			)
			(layer "F.Fab")
		)
		(fp_line
			(start -0.12065 0.3048)
			(end -0.67945 0.3048)
			(stroke
				(width 0.1)
				(type default)
			)
			(layer "F.Fab")
		)
		(fp_line
			(start -0.67945 0.3048)
			(end -0.67945 -0.305054)
			(stroke
				(width 0.1)
				(type default)
			)
			(layer "F.Fab")
		)
		(pad "1" smd circle
			(at -0.40005 0 90)
			(size 0 0)
			(layers "F.Cu" "F.Mask" "F.Paste")
			(net "RST_SMB_SSD4_ISO_R_N")
		)
		(pad "2" smd circle
			(at 0.40005 0 90)
			(size 0 0)
			(layers "F.Cu" "F.Mask" "F.Paste")
			(net "RST_SMB_SSD4_ISO_N")
		)
	)
	(footprint ""
		(layer "F.Cu")
		(at 23.737824 -166.07155 -90)
		(property "Reference" "PC18"
			(at 0 0 270)
			(layer "F.SilkS")
			(hide yes)
			(effects
				(font
					(size 1.27 1.27)
				)
			)
		)
		(property "Value" ""
			(at 0 0 270)
			(layer "F.Fab")
			(effects
				(font
					(size 1.27 1.27)
				)
			)
		)
		(duplicate_pad_numbers_are_jumpers no)
		(fp_line
			(start -0.7874 0.4064)
			(end -0.7874 -0.4064)
			(stroke
				(width 0.1524)
				(type default)
			)
			(layer "F.SilkS")
		)
		(fp_line
			(start 0.7874 0.4064)
			(end -0.7874 0.4064)
			(stroke
				(width 0.1524)
				(type default)
			)
			(layer "F.SilkS")
		)
		(fp_line
			(start -0.7874 -0.4064)
			(end 0.7874 -0.4064)
			(stroke
				(width 0.1524)
				(type default)
			)
			(layer "F.SilkS")
		)
		(fp_line
			(start 0.7874 -0.4064)
			(end 0.7874 0.4064)
			(stroke
				(width 0.1524)
				(type default)
			)
			(layer "F.SilkS")
		)
		(fp_line
			(start -0.67945 0.3048)
			(end -0.67945 -0.305054)
			(stroke
				(width 0.1)
				(type default)
			)
			(layer "F.Fab")
		)
		(fp_line
			(start -0.12065 0.3048)
			(end -0.67945 0.3048)
			(stroke
				(width 0.1)
				(type default)
			)
			(layer "F.Fab")
		)
		(fp_line
			(start 0.120396 0.3048)
			(end 0.120396 0.2794)
			(stroke
				(width 0.1)
				(type default)
			)
			(layer "F.Fab")
		)
		(fp_line
			(start 0.67945 0.3048)
			(end 0.120396 0.3048)
			(stroke
				(width 0.1)
				(type default)
			)
			(layer "F.Fab")
		)
		(fp_line
			(start -0.12065 0.2794)
			(end -0.12065 0.3048)
			(stroke
				(width 0.1)
				(type default)
			)
			(layer "F.Fab")
		)
		(fp_line
			(start 0.120396 0.2794)
			(end -0.12065 0.2794)
			(stroke
				(width 0.1)
				(type default)
			)
			(layer "F.Fab")
		)
		(fp_line
			(start -0.12065 -0.2794)
			(end 0.12065 -0.2794)
			(stroke
				(width 0.1)
				(type default)
			)
			(layer "F.Fab")
		)
		(fp_line
			(start 0.12065 -0.2794)
			(end 0.12065 -0.3048)
			(stroke
				(width 0.1)
				(type default)
			)
			(layer "F.Fab")
		)
		(fp_line
			(start 0.12065 -0.3048)
			(end 0.67945 -0.3048)
			(stroke
				(width 0.1)
				(type default)
			)
			(layer "F.Fab")
		)
		(fp_line
			(start 0.67945 -0.3048)
			(end 0.67945 0.3048)
			(stroke
				(width 0.1)
				(type default)
			)
			(layer "F.Fab")
		)
		(fp_line
			(start -0.67945 -0.305054)
			(end -0.12065 -0.305054)
			(stroke
				(width 0.1)
				(type default)
			)
			(layer "F.Fab")
		)
		(fp_line
			(start -0.12065 -0.305054)
			(end -0.12065 -0.2794)
			(stroke
				(width 0.1)
				(type default)
			)
			(layer "F.Fab")
		)
		(pad "1" smd circle
			(at -0.40005 0 270)
			(size 0 0)
			(layers "F.Cu" "F.Mask" "F.Paste")
			(net "P12V_AUX")
		)
		(pad "2" smd circle
			(at 0.40005 0 270)
			(size 0 0)
			(layers "F.Cu" "F.Mask" "F.Paste")
			(net "GND")
		)
	)
	(footprint ""
		(layer "F.Cu")
		(at 422.185592 -27.092148 -90)
		(property "Reference" "R5747"
			(at 0 0 270)
			(layer "F.SilkS")
			(hide yes)
			(effects
				(font
					(size 1.27 1.27)
				)
			)
		)
		(property "Value" ""
			(at 0 0 270)
			(layer "F.Fab")
			(effects
				(font
					(size 1.27 1.27)
				)
			)
		)
		(duplicate_pad_numbers_are_jumpers no)
		(fp_line
			(start -0.7874 0.4064)
			(end -0.7874 -0.4064)
			(stroke
				(width 0.1524)
				(type default)
			)
			(layer "F.SilkS")
		)
		(fp_line
			(start 0.7874 0.4064)
			(end -0.7874 0.4064)
			(stroke
				(width 0.1524)
				(type default)
			)
			(layer "F.SilkS")
		)
		(fp_line
			(start -0.7874 -0.4064)
			(end 0.7874 -0.4064)
			(stroke
				(width 0.1524)
				(type default)
			)
			(layer "F.SilkS")
		)
		(fp_line
			(start 0.7874 -0.4064)
			(end 0.7874 0.4064)
			(stroke
				(width 0.1524)
				(type default)
			)
			(layer "F.SilkS")
		)
		(fp_line
			(start -0.67945 0.3048)
			(end -0.67945 -0.305054)
			(stroke
				(width 0.1)
				(type default)
			)
			(layer "F.Fab")
		)
		(fp_line
			(start -0.12065 0.3048)
			(end -0.67945 0.3048)
			(stroke
				(width 0.1)
				(type default)
			)
			(layer "F.Fab")
		)
		(fp_line
			(start 0.120396 0.3048)
			(end 0.120396 0.2794)
			(stroke
				(width 0.1)
				(type default)
			)
			(layer "F.Fab")
		)
		(fp_line
			(start 0.67945 0.3048)
			(end 0.120396 0.3048)
			(stroke
				(width 0.1)
				(type default)
			)
			(layer "F.Fab")
		)
		(fp_line
			(start -0.12065 0.2794)
			(end -0.12065 0.3048)
			(stroke
				(width 0.1)
				(type default)
			)
			(layer "F.Fab")
		)
		(fp_line
			(start 0.120396 0.2794)
			(end -0.12065 0.2794)
			(stroke
				(width 0.1)
				(type default)
			)
			(layer "F.Fab")
		)
		(fp_line
			(start -0.12065 -0.2794)
			(end 0.12065 -0.2794)
			(stroke
				(width 0.1)
				(type default)
			)
			(layer "F.Fab")
		)
		(fp_line
			(start 0.12065 -0.2794)
			(end 0.12065 -0.3048)
			(stroke
				(width 0.1)
				(type default)
			)
			(layer "F.Fab")
		)
		(fp_line
			(start 0.12065 -0.3048)
			(end 0.67945 -0.3048)
			(stroke
				(width 0.1)
				(type default)
			)
			(layer "F.Fab")
		)
		(fp_line
			(start 0.67945 -0.3048)
			(end 0.67945 0.3048)
			(stroke
				(width 0.1)
				(type default)
			)
			(layer "F.Fab")
		)
		(fp_line
			(start -0.67945 -0.305054)
			(end -0.12065 -0.305054)
			(stroke
				(width 0.1)
				(type default)
			)
			(layer "F.Fab")
		)
		(fp_line
			(start -0.12065 -0.305054)
			(end -0.12065 -0.2794)
			(stroke
				(width 0.1)
				(type default)
			)
			(layer "F.Fab")
		)
		(pad "1" smd circle
			(at -0.40005 0 270)
			(size 0 0)
			(layers "F.Cu" "F.Mask" "F.Paste")
			(net "P3V3_SSD14")
		)
		(pad "2" smd circle
			(at 0.40005 0 270)
			(size 0 0)
			(layers "F.Cu" "F.Mask" "F.Paste")
			(net "SSD14_LED_ISO_N")
		)
	)
	(footprint ""
		(layer "F.Cu")
		(at 198.76135 -152.511252 180)
		(property "Reference" "C216"
			(at 0 0 180)
			(layer "F.SilkS")
			(hide yes)
			(effects
				(font
					(size 1.27 1.27)
				)
			)
		)
		(property "Value" ""
			(at 0 0 180)
			(layer "F.Fab")
			(effects
				(font
					(size 1.27 1.27)
				)
			)
		)
		(duplicate_pad_numbers_are_jumpers no)
		(fp_line
			(start 0.299974 0.150114)
			(end -0.299974 0.150114)
			(stroke
				(width 0.1)
				(type default)
			)
			(layer "F.Fab")
		)
		(fp_line
			(start 0.299974 -0.150114)
			(end 0.299974 0.150114)
			(stroke
				(width 0.1)
				(type default)
			)
			(layer "F.Fab")
		)
		(fp_line
			(start -0.299974 0.150114)
			(end -0.299974 -0.150114)
			(stroke
				(width 0.1)
				(type default)
			)
			(layer "F.Fab")
		)
		(fp_line
			(start -0.299974 -0.150114)
			(end 0.299974 -0.150114)
			(stroke
				(width 0.1)
				(type default)
			)
			(layer "F.Fab")
		)
		(pad "1" smd rect
			(at -0.2667 0 180)
			(size 0.3048 0.381)
			(layers "F.Cu" "F.Mask" "F.Paste")
			(net "P5E_PEX1_STN0_TX_DP<13>")
		)
		(pad "2" smd rect
			(at 0.2667 0 180)
			(size 0.3048 0.381)
			(layers "F.Cu" "F.Mask" "F.Paste")
			(net "P5E_PEX1_STN0_TX_C_DP<13>")
		)
	)
)
